# S9S_MB_2U (Grand Teton) — schematic netlist excerpt (pin names and nets, part order shuffled) for the footprints in the layout excerpt that follows; sources: Cadence DE-HDL packaged netlist, KiCad conversion of 03242023_DA0F0TMBIJ0_F0T_Motherboard_J_brd_V01_OCP.brd

R2836  Q_RES  4.7K 5% CHIP  pkg 0402LF  page 148 : A = P3V3_AUX ; B = FM_SWB_BIC_READY
R1497  Q_RES  12K 1% EMPTY  pkg 0402LF  page 200 : A = FM_PCH_DFXTESTMODE ; B = GND

(kicad_pcb
	(version 20260206)
	(generator "pcbnew")
	(generator_version "10.0")
	(general
		(thickness 1.6)
		(legacy_teardrops no)
	)
	(paper "A4")
	(title_block
		(title "03242023_DA0F0TMBIJ0_F0T_Motherboard_J_brd_V01_OCP.brd")
		(comment 1 "Grand Teton / footprints 3125-3126 of 6105")
	)
	(layers
		(0 "F.Cu" signal "TOP")
		(4 "In1.Cu" signal "GND")
		(6 "In2.Cu" signal "IN1")
		(8 "In3.Cu" signal "GND1")
		(10 "In4.Cu" signal "IN2")
		(12 "In5.Cu" signal "GND2")
		(14 "In6.Cu" signal "IN3")
		(16 "In7.Cu" signal "GND3")
		(18 "In8.Cu" signal "VCC")
		(20 "In9.Cu" signal "VCC1")
		(22 "In10.Cu" signal "GND4")
		(24 "In11.Cu" signal "IN4")
		(26 "In12.Cu" signal "GND5")
		(28 "In13.Cu" signal "IN5")
		(30 "In14.Cu" signal "GND6")
		(32 "In15.Cu" signal "IN6")
		(34 "In16.Cu" signal "GND7")
		(2 "B.Cu" signal "BOTTOM")
		(9 "F.Adhes" user "F.Adhesive")
		(11 "B.Adhes" user "B.Adhesive")
		(13 "F.Paste" user "Package Geometry/Pastemask Top")
		(15 "B.Paste" user "Package Geometry/Pastemask Bottom")
		(5 "F.SilkS" user "Ref Des/Silkscreen Top")
		(7 "B.SilkS" user "Ref Des/Silkscreen Bottom")
		(1 "F.Mask" user "Board Geometry/Soldermask Top")
		(3 "B.Mask" user "Board Geometry/Soldermask Bottom")
		(17 "Dwgs.User" user "User.Drawings")
		(19 "Cmts.User" user "User.Comments")
		(21 "Eco1.User" user "User.Eco1")
		(23 "Eco2.User" user "User.Eco2")
		(25 "Edge.Cuts" user "Board Geometry/Outline")
		(27 "Margin" user)
		(31 "F.CrtYd" user "Package Geometry/Place Bound Top")
		(29 "B.CrtYd" user "Package Geometry/Place Bound Bottom")
		(35 "F.Fab" user "Ref Des/Assembly Top")
		(33 "B.Fab" user "Ref Des/Assembly Bottom")
	)
	(footprint ""
		(layer "F.Cu")
		(at 431.989992 -391.505948 180)
		(property "Reference" "R2836"
			(at 0 0 180)
			(layer "F.SilkS")
			(hide yes)
			(effects
				(font
					(size 1.27 1.27)
				)
			)
		)
		(property "Value" ""
			(at 0 0 180)
			(layer "F.Fab")
			(effects
				(font
					(size 1.27 1.27)
				)
			)
		)
		(duplicate_pad_numbers_are_jumpers no)
		(fp_line
			(start 0.7874 0.4064)
			(end -0.7874 0.4064)
			(stroke
				(width 0.1524)
				(type default)
			)
			(layer "F.SilkS")
		)
		(fp_line
			(start 0.7874 -0.4064)
			(end 0.7874 0.4064)
			(stroke
				(width 0.1524)
				(type default)
			)
			(layer "F.SilkS")
		)
		(fp_line
			(start -0.7874 0.4064)
			(end -0.7874 -0.4064)
			(stroke
				(width 0.1524)
				(type default)
			)
			(layer "F.SilkS")
		)
		(fp_line
			(start -0.7874 -0.4064)
			(end 0.7874 -0.4064)
			(stroke
				(width 0.1524)
				(type default)
			)
			(layer "F.SilkS")
		)
		(fp_line
			(start 0.67945 0.3048)
			(end 0.120396 0.3048)
			(stroke
				(width 0.1)
				(type default)
			)
			(layer "F.Fab")
		)
		(fp_line
			(start 0.67945 -0.3048)
			(end 0.67945 0.3048)
			(stroke
				(width 0.1)
				(type default)
			)
			(layer "F.Fab")
		)
		(fp_line
			(start 0.12065 -0.2794)
			(end 0.12065 -0.3048)
			(stroke
				(width 0.1)
				(type default)
			)
			(layer "F.Fab")
		)
		(fp_line
			(start 0.12065 -0.3048)
			(end 0.67945 -0.3048)
			(stroke
				(width 0.1)
				(type default)
			)
			(layer "F.Fab")
		)
		(fp_line
			(start 0.120396 0.3048)
			(end 0.120396 0.2794)
			(stroke
				(width 0.1)
				(type default)
			)
			(layer "F.Fab")
		)
		(fp_line
			(start 0.120396 0.2794)
			(end -0.12065 0.2794)
			(stroke
				(width 0.1)
				(type default)
			)
			(layer "F.Fab")
		)
		(fp_line
			(start -0.12065 0.3048)
			(end -0.67945 0.3048)
			(stroke
				(width 0.1)
				(type default)
			)
			(layer "F.Fab")
		)
		(fp_line
			(start -0.12065 0.2794)
			(end -0.12065 0.3048)
			(stroke
				(width 0.1)
				(type default)
			)
			(layer "F.Fab")
		)
		(fp_line
			(start -0.12065 -0.2794)
			(end 0.12065 -0.2794)
			(stroke
				(width 0.1)
				(type default)
			)
			(layer "F.Fab")
		)
		(fp_line
			(start -0.12065 -0.305054)
			(end -0.12065 -0.2794)
			(stroke
				(width 0.1)
				(type default)
			)
			(layer "F.Fab")
		)
		(fp_line
			(start -0.67945 0.3048)
			(end -0.67945 -0.305054)
			(stroke
				(width 0.1)
				(type default)
			)
			(layer "F.Fab")
		)
		(fp_line
			(start -0.67945 -0.305054)
			(end -0.12065 -0.305054)
			(stroke
				(width 0.1)
				(type default)
			)
			(layer "F.Fab")
		)
		(pad "1" smd circle
			(at -0.40005 0 180)
			(size 0 0)
			(layers "F.Cu" "F.Mask" "F.Paste")
			(net "P3V3_AUX")
		)
		(pad "2" smd circle
			(at 0.40005 0 180)
			(size 0 0)
			(layers "F.Cu" "F.Mask" "F.Paste")
			(net "FM_SWB_BIC_READY")
		)
	)
	(footprint ""
		(layer "F.Cu")
		(at 315.110622 -55.235348 180)
		(property "Reference" "R1497"
			(at 0 0 180)
			(layer "F.SilkS")
			(hide yes)
			(effects
				(font
					(size 1.27 1.27)
				)
			)
		)
		(property "Value" ""
			(at 0 0 180)
			(layer "F.Fab")
			(effects
				(font
					(size 1.27 1.27)
				)
			)
		)
		(duplicate_pad_numbers_are_jumpers no)
		(fp_line
			(start 0.7874 0.4064)
			(end -0.7874 0.4064)
			(stroke
				(width 0.1524)
				(type default)
			)
			(layer "F.SilkS")
		)
		(fp_line
			(start 0.7874 -0.4064)
			(end 0.7874 0.4064)
			(stroke
				(width 0.1524)
				(type default)
			)
			(layer "F.SilkS")
		)
		(fp_line
			(start -0.7874 0.4064)
			(end -0.7874 -0.4064)
			(stroke
				(width 0.1524)
				(type default)
			)
			(layer "F.SilkS")
		)
		(fp_line
			(start -0.7874 -0.4064)
			(end 0.7874 -0.4064)
			(stroke
				(width 0.1524)
				(type default)
			)
			(layer "F.SilkS")
		)
		(fp_line
			(start 0.67945 0.3048)
			(end 0.120396 0.3048)
			(stroke
				(width 0.1)
				(type default)
			)
			(layer "F.Fab")
		)
		(fp_line
			(start 0.67945 -0.3048)
			(end 0.67945 0.3048)
			(stroke
				(width 0.1)
				(type default)
			)
			(layer "F.Fab")
		)
		(fp_line
			(start 0.12065 -0.2794)
			(end 0.12065 -0.3048)
			(stroke
				(width 0.1)
				(type default)
			)
			(layer "F.Fab")
		)
		(fp_line
			(start 0.12065 -0.3048)
			(end 0.67945 -0.3048)
			(stroke
				(width 0.1)
				(type default)
			)
			(layer "F.Fab")
		)
		(fp_line
			(start 0.120396 0.3048)
			(end 0.120396 0.2794)
			(stroke
				(width 0.1)
				(type default)
			)
			(layer "F.Fab")
		)
		(fp_line
			(start 0.120396 0.2794)
			(end -0.12065 0.2794)
			(stroke
				(width 0.1)
				(type default)
			)
			(layer "F.Fab")
		)
		(fp_line
			(start -0.12065 0.3048)
			(end -0.67945 0.3048)
			(stroke
				(width 0.1)
				(type default)
			)
			(layer "F.Fab")
		)
		(fp_line
			(start -0.12065 0.2794)
			(end -0.12065 0.3048)
			(stroke
				(width 0.1)
				(type default)
			)
			(layer "F.Fab")
		)
		(fp_line
			(start -0.12065 -0.2794)
			(end 0.12065 -0.2794)
			(stroke
				(width 0.1)
				(type default)
			)
			(layer "F.Fab")
		)
		(fp_line
			(start -0.12065 -0.305054)
			(end -0.12065 -0.2794)
			(stroke
				(width 0.1)
				(type default)
			)
			(layer "F.Fab")
		)
		(fp_line
			(start -0.67945 0.3048)
			(end -0.67945 -0.305054)
			(stroke
				(width 0.1)
				(type default)
			)
			(layer "F.Fab")
		)
		(fp_line
			(start -0.67945 -0.305054)
			(end -0.12065 -0.305054)
			(stroke
				(width 0.1)
				(type default)
			)
			(layer "F.Fab")
		)
		(pad "1" smd circle
			(at -0.40005 0 180)
			(size 0 0)
			(layers "F.Cu" "F.Mask" "F.Paste")
			(net "FM_PCH_DFXTESTMODE")
		)
		(pad "2" smd circle
			(at 0.40005 0 180)
			(size 0 0)
			(layers "F.Cu" "F.Mask" "F.Paste")
			(net "GND")
		)
	)
)
